(kicad_pcb
	(version 20260206)
	(generator "pcbnew")
	(generator_version "10.0")
	(general
		(thickness 1.6)
		(legacy_teardrops no)
	)
	(paper "A4")
	(title_block
		(title "Bryce Canyon_F.DPB_16315-1-OCP.brd")
		(comment 1 "Bryce Canyon / footprints 853-860 of 2223")
	)
	(layers
		(0 "F.Cu" signal "TOP")
		(4 "In1.Cu" signal "L2GND")
		(6 "In2.Cu" signal "L3")
		(8 "In3.Cu" signal "L4GND")
		(10 "In4.Cu" signal "L5")
		(12 "In5.Cu" signal "L6VCC")
		(14 "In6.Cu" signal "L7VCC")
		(16 "In7.Cu" signal "L8")
		(18 "In8.Cu" signal "L9GND")
		(20 "In9.Cu" signal "L10")
		(22 "In10.Cu" signal "L11GND")
		(2 "B.Cu" signal "BOTTOM")
		(9 "F.Adhes" user "F.Adhesive")
		(11 "B.Adhes" user "B.Adhesive")
		(13 "F.Paste" user "Package Geometry/Pastemask Top")
		(15 "B.Paste" user "Package Geometry/Pastemask Bottom")
		(5 "F.SilkS" user "Ref Des/Silkscreen Top")
		(7 "B.SilkS" user "Ref Des/Silkscreen Bottom")
		(1 "F.Mask" user "Board Geometry/Soldermask Top")
		(3 "B.Mask" user "Board Geometry/Soldermask Bottom")
		(17 "Dwgs.User" user "User.Drawings")
		(19 "Cmts.User" user "User.Comments")
		(21 "Eco1.User" user "User.Eco1")
		(23 "Eco2.User" user "User.Eco2")
		(25 "Edge.Cuts" user "Board Geometry/Outline")
		(27 "Margin" user)
		(31 "F.CrtYd" user "Package Geometry/Place Bound Top")
		(29 "B.CrtYd" user "Package Geometry/Place Bound Bottom")
		(35 "F.Fab" user "Ref Des/Assembly Top")
		(33 "B.Fab" user "Ref Des/Assembly Bottom")
	)
	(footprint ""
		(layer "F.Cu")
		(at 46.265846 -179.683918 -90)
		(property "Reference" "C213"
			(at 0 0 270)
			(layer "F.SilkS")
			(hide yes)
			(effects
				(font
					(size 1.27 1.27)
				)
			)
		)
		(property "Value" "SC4D7U25V5KX-1-GP"
			(at -0.0762 -6.1214 270)
			(unlocked yes)
			(layer "F.Fab")
			(hide yes)
			(effects
				(font
					(size 1.016 1.016)
					(thickness 0.1524)
				)
			)
		)
		(property "Device Type" "C805H58"
			(at -0.0762 -8.1534 270)
			(unlocked yes)
			(layer "F.Fab")
			(hide yes)
			(effects
				(font
					(size 1.016 1.016)
					(thickness 0.1524)
				)
			)
		)
		(duplicate_pad_numbers_are_jumpers no)
		(fp_line
			(start 0.635 0)
			(end -0.635 0)
			(stroke
				(width 0.508)
				(type default)
			)
			(layer "F.SilkS")
		)
		(fp_rect
			(start -0.9652 1.778)
			(end 0.9652 -1.778)
			(stroke
				(width 0)
				(type default)
			)
			(fill no)
			(layer "F.CrtYd")
		)
		(fp_poly
			(pts
				(xy -0.9652 -1.778) (xy 0.9652 -1.778) (xy 0.9652 1.778) (xy -0.9652 1.778)
			)
			(stroke
				(width 0)
				(type default)
			)
			(fill no)
			(layer "F.Fab")
		)
		(pad "1" smd rect
			(at 0 -0.9652 270)
			(size 1.397 1.143)
			(layers "F.Cu" "F.Mask" "F.Paste")
			(net "P12V_HDD13")
		)
		(pad "2" smd rect
			(at 0 0.9652 270)
			(size 1.397 1.143)
			(layers "F.Cu" "F.Mask" "F.Paste")
			(net "GND")
		)
	)
	(footprint ""
		(layer "F.Cu")
		(at 343.038684 -245.28907 -90)
		(property "Reference" "R481"
			(at 0 0 270)
			(layer "F.SilkS")
			(hide yes)
			(effects
				(font
					(size 1.27 1.27)
				)
			)
		)
		(property "Value" "4K7R2J-2-GP"
			(at 0.064008 -3.993896 270)
			(unlocked yes)
			(layer "F.Fab")
			(hide yes)
			(effects
				(font
					(size 1.016 1.016)
					(thickness 0.1524)
				)
			)
		)
		(property "Device Type" "R402H16"
			(at 0.064008 -5.517896 270)
			(unlocked yes)
			(layer "F.Fab")
			(hide yes)
			(effects
				(font
					(size 1.016 1.016)
					(thickness 0.1524)
				)
			)
		)
		(duplicate_pad_numbers_are_jumpers no)
		(fp_line
			(start -0.508 -0.9398)
			(end -0.508 0.9398)
			(stroke
				(width 0.1524)
				(type default)
			)
			(layer "F.SilkS")
		)
		(fp_line
			(start 0.508 -0.9398)
			(end -0.508 -0.9398)
			(stroke
				(width 0.1524)
				(type default)
			)
			(layer "F.SilkS")
		)
		(fp_rect
			(start -0.508 0.9398)
			(end 0.508 -0.9398)
			(stroke
				(width 0)
				(type default)
			)
			(fill no)
			(layer "F.CrtYd")
		)
		(fp_rect
			(start -0.508 0.9398)
			(end 0.508 -0.9398)
			(stroke
				(width 0)
				(type default)
			)
			(fill no)
			(layer "F.Fab")
		)
		(pad "1" smd custom
			(at 0 -0.4445 270)
			(size 0.1397 0.1397)
			(layers "F.Cu" "F.Mask" "F.Paste")
			(net "DRIVE_A_7_FLT_LED")
			(options
				(clearance outline)
				(anchor circle)
			)
			(primitives
				(gr_poly
					(pts
						(arc
							(start -0.1778 -0.2794)
							(mid -0.249642 -0.249642)
							(end -0.2794 -0.1778)
						)
						(arc
							(start -0.2794 0.1778)
							(mid -0.249642 0.249642)
							(end -0.1778 0.2794)
						)
						(arc
							(start 0.1778 0.2794)
							(mid 0.249642 0.249642)
							(end 0.2794 0.1778)
						)
						(arc
							(start 0.2794 -0.1778)
							(mid 0.249642 -0.249642)
							(end 0.1778 -0.2794)
						)
					)
					(width 0)
					(fill yes)
				)
			)
		)
		(pad "2" smd custom
			(at 0 0.4445 270)
			(size 0.1397 0.1397)
			(layers "F.Cu" "F.Mask" "F.Paste")
			(net "GND")
			(options
				(clearance outline)
				(anchor circle)
			)
			(primitives
				(gr_poly
					(pts
						(arc
							(start -0.1778 -0.2794)
							(mid -0.249642 -0.249642)
							(end -0.2794 -0.1778)
						)
						(arc
							(start -0.2794 0.1778)
							(mid -0.249642 0.249642)
							(end -0.1778 0.2794)
						)
						(arc
							(start 0.1778 0.2794)
							(mid 0.249642 0.249642)
							(end 0.2794 0.1778)
						)
						(arc
							(start 0.2794 -0.1778)
							(mid 0.249642 -0.249642)
							(end 0.1778 -0.2794)
						)
					)
					(width 0)
					(fill yes)
				)
			)
		)
	)
	(footprint ""
		(layer "F.Cu")
		(at 47.866046 -285.412942 90)
		(property "Reference" "C62"
			(at 0 0 90)
			(layer "F.SilkS")
			(hide yes)
			(effects
				(font
					(size 1.27 1.27)
				)
			)
		)
		(property "Value" "SCD033U25V2KX-GP"
			(at 1.1811 -2.7051 90)
			(unlocked yes)
			(layer "F.Fab")
			(hide yes)
			(effects
				(font
					(size 1.016 1.016)
					(thickness 0.1524)
				)
			)
		)
		(property "Device Type" "C402H22"
			(at 1.1811 -4.2291 90)
			(unlocked yes)
			(layer "F.Fab")
			(hide yes)
			(effects
				(font
					(size 1.016 1.016)
					(thickness 0.1524)
				)
			)
		)
		(duplicate_pad_numbers_are_jumpers no)
		(fp_rect
			(start -0.4318 0.9525)
			(end 0.4318 -0.9525)
			(stroke
				(width 0)
				(type default)
			)
			(fill no)
			(layer "F.CrtYd")
		)
		(fp_rect
			(start -0.4318 0.9525)
			(end 0.4318 -0.9525)
			(stroke
				(width 0)
				(type default)
			)
			(fill no)
			(layer "F.Fab")
		)
		(pad "1" smd custom
			(at 0 -0.4445 90)
			(size 0.1524 0.1524)
			(layers "F.Cu" "F.Mask" "F.Paste")
			(net "P12V_A")
			(options
				(clearance outline)
				(anchor circle)
			)
			(primitives
				(gr_poly
					(pts
						(arc
							(start 0.3048 -0.2032)
							(mid 0.275042 -0.275042)
							(end 0.2032 -0.3048)
						)
						(arc
							(start -0.2032 -0.3048)
							(mid -0.275042 -0.275042)
							(end -0.3048 -0.2032)
						)
						(arc
							(start -0.3048 0.2032)
							(mid -0.275042 0.275042)
							(end -0.2032 0.3048)
						)
						(arc
							(start 0.2032 0.3048)
							(mid 0.275042 0.275042)
							(end 0.3048 0.2032)
						)
					)
					(width 0)
					(fill yes)
				)
			)
		)
		(pad "2" smd custom
			(at 0 0.4445 90)
			(size 0.1524 0.1524)
			(layers "F.Cu" "F.Mask" "F.Paste")
			(net "SW_HDD_N1")
			(options
				(clearance outline)
				(anchor circle)
			)
			(primitives
				(gr_poly
					(pts
						(arc
							(start 0.3048 -0.2032)
							(mid 0.275042 -0.275042)
							(end 0.2032 -0.3048)
						)
						(arc
							(start -0.2032 -0.3048)
							(mid -0.275042 -0.275042)
							(end -0.3048 -0.2032)
						)
						(arc
							(start -0.3048 0.2032)
							(mid -0.275042 0.275042)
							(end -0.2032 0.3048)
						)
						(arc
							(start 0.2032 0.3048)
							(mid 0.275042 0.275042)
							(end 0.3048 0.2032)
						)
					)
					(width 0)
					(fill yes)
				)
			)
		)
	)
	(footprint ""
		(layer "F.Cu")
		(at 470.021158 -293.887144)
		(property "Reference" "Q300"
			(at 0 0 0)
			(layer "F.SilkS")
			(hide yes)
			(effects
				(font
					(size 1.27 1.27)
				)
			)
		)
		(property "Value" "2N7002K-2-GP"
			(at 0.127 -8.9662 0)
			(unlocked yes)
			(layer "F.Fab")
			(hide yes)
			(effects
				(font
					(size 1.016 1.016)
					(thickness 0.1524)
				)
			)
		)
		(property "Device Type" "SOT23DGS2D4H44"
			(at 0.127 -10.4902 0)
			(unlocked yes)
			(layer "F.Fab")
			(hide yes)
			(effects
				(font
					(size 1.016 1.016)
					(thickness 0.1524)
				)
			)
		)
		(duplicate_pad_numbers_are_jumpers no)
		(fp_line
			(start -1.651 -1.778)
			(end -1.651 1.778)
			(stroke
				(width 0.1524)
				(type default)
			)
			(layer "F.SilkS")
		)
		(fp_line
			(start -1.651 1.778)
			(end 1.651 1.778)
			(stroke
				(width 0.1524)
				(type default)
			)
			(layer "F.SilkS")
		)
		(fp_line
			(start 1.651 -1.778)
			(end -1.651 -1.778)
			(stroke
				(width 0.1524)
				(type default)
			)
			(layer "F.SilkS")
		)
		(fp_line
			(start 1.651 1.778)
			(end 1.651 -1.778)
			(stroke
				(width 0.1524)
				(type default)
			)
			(layer "F.SilkS")
		)
		(fp_poly
			(pts
				(xy -1.778 1.8796) (xy -1.778 -1.8796) (xy 1.778 -1.8796) (xy 1.778 1.8796)
			)
			(stroke
				(width 0)
				(type default)
			)
			(fill no)
			(layer "F.CrtYd")
		)
		(fp_poly
			(pts
				(xy -1.778 1.8796) (xy -1.778 -1.8796) (xy 1.778 -1.8796) (xy 1.778 1.8796)
			)
			(stroke
				(width 0)
				(type default)
			)
			(fill no)
			(layer "F.Fab")
		)
		(pad "D" smd custom
			(at 0 -0.9525)
			(size 0.1905 0.1905)
			(layers "F.Cu" "F.Mask" "F.Paste")
			(net "FLT_HDD35_N")
			(options
				(clearance outline)
				(anchor circle)
			)
			(primitives
				(gr_poly
					(pts
						(arc
							(start -0.1778 0.5715)
							(mid -0.321484 0.511984)
							(end -0.381 0.3683)
						)
						(arc
							(start -0.381 -0.3683)
							(mid -0.321484 -0.511984)
							(end -0.1778 -0.5715)
						)
						(arc
							(start 0.1778 -0.5715)
							(mid 0.321484 -0.511984)
							(end 0.381 -0.3683)
						)
						(arc
							(start 0.381 0.3683)
							(mid 0.321484 0.511984)
							(end 0.1778 0.5715)
						)
					)
					(width 0)
					(fill yes)
				)
			)
		)
		(pad "G" smd custom
			(at -0.98425 0.9525)
			(size 0.1905 0.1905)
			(layers "F.Cu" "F.Mask" "F.Paste")
			(net "DRIVE_B_35_FLT_LED")
			(options
				(clearance outline)
				(anchor circle)
			)
			(primitives
				(gr_poly
					(pts
						(arc
							(start -0.1778 0.5715)
							(mid -0.321484 0.511984)
							(end -0.381 0.3683)
						)
						(arc
							(start -0.381 -0.3683)
							(mid -0.321484 -0.511984)
							(end -0.1778 -0.5715)
						)
						(arc
							(start 0.1778 -0.5715)
							(mid 0.321484 -0.511984)
							(end 0.381 -0.3683)
						)
						(arc
							(start 0.381 0.3683)
							(mid 0.321484 0.511984)
							(end 0.1778 0.5715)
						)
					)
					(width 0)
					(fill yes)
				)
			)
		)
		(pad "S" smd custom
			(at 0.98425 0.9525)
			(size 0.1905 0.1905)
			(layers "F.Cu" "F.Mask" "F.Paste")
			(net "GND")
			(options
				(clearance outline)
				(anchor circle)
			)
			(primitives
				(gr_poly
					(pts
						(arc
							(start -0.1778 0.5715)
							(mid -0.321484 0.511984)
							(end -0.381 0.3683)
						)
						(arc
							(start -0.381 -0.3683)
							(mid -0.321484 -0.511984)
							(end -0.1778 -0.5715)
						)
						(arc
							(start 0.1778 -0.5715)
							(mid 0.321484 -0.511984)
							(end 0.381 -0.3683)
						)
						(arc
							(start 0.381 0.3683)
							(mid 0.321484 0.511984)
							(end 0.1778 0.5715)
						)
					)
					(width 0)
					(fill yes)
				)
			)
		)
	)
	(footprint ""
		(layer "F.Cu")
		(at 177.8 -291.000942 -90)
		(property "Reference" "C106"
			(at 0 0 270)
			(layer "F.SilkS")
			(hide yes)
			(effects
				(font
					(size 1.27 1.27)
				)
			)
		)
		(property "Value" "SC10U16V6KX-2GP"
			(at -0.0762 -5.1308 270)
			(unlocked yes)
			(layer "F.Fab")
			(hide yes)
			(effects
				(font
					(size 1.016 1.016)
					(thickness 0.1524)
				)
			)
		)
		(property "Device Type" "C1206H71"
			(at -0.127 -6.6548 270)
			(unlocked yes)
			(layer "F.Fab")
			(hide yes)
			(effects
				(font
					(size 1.016 1.016)
					(thickness 0.1524)
				)
			)
		)
		(duplicate_pad_numbers_are_jumpers no)
		(fp_line
			(start -1.016 2.2352)
			(end -1.016 0.8382)
			(stroke
				(width 0.1524)
				(type default)
			)
			(layer "F.SilkS")
		)
		(fp_line
			(start 1.016 2.2352)
			(end -1.016 2.2352)
			(stroke
				(width 0.1524)
				(type default)
			)
			(layer "F.SilkS")
		)
		(fp_line
			(start 1.016 0.8382)
			(end 1.016 2.2352)
			(stroke
				(width 0.1524)
				(type default)
			)
			(layer "F.SilkS")
		)
		(fp_line
			(start -1.016 -0.8382)
			(end -1.016 -2.2352)
			(stroke
				(width 0.1524)
				(type default)
			)
			(layer "F.SilkS")
		)
		(fp_line
			(start -1.016 -2.2352)
			(end 1.016 -2.2352)
			(stroke
				(width 0.1524)
				(type default)
			)
			(layer "F.SilkS")
		)
		(fp_line
			(start 1.016 -2.2352)
			(end 1.016 -0.8382)
			(stroke
				(width 0.1524)
				(type default)
			)
			(layer "F.SilkS")
		)
		(fp_rect
			(start -1.0922 2.3114)
			(end 1.0922 -2.3114)
			(stroke
				(width 0)
				(type default)
			)
			(fill no)
			(layer "F.CrtYd")
		)
		(fp_poly
			(pts
				(xy 1.0922 -2.3114) (xy 1.0922 2.3114) (xy -1.0922 2.3114) (xy -1.0922 -2.3114)
			)
			(stroke
				(width 0)
				(type default)
			)
			(fill no)
			(layer "F.Fab")
		)
		(pad "1" smd rect
			(at 0 -1.397 270)
			(size 1.651 1.27)
			(layers "F.Cu" "F.Mask" "F.Paste")
			(net "P5V_HDD5")
		)
		(pad "2" smd rect
			(at 0 1.397 270)
			(size 1.651 1.27)
			(layers "F.Cu" "F.Mask" "F.Paste")
			(net "GND")
		)
	)
	(footprint ""
		(layer "F.Cu")
		(at 332.359 -65.826894 180)
		(property "Reference" "C431"
			(at 0 0 180)
			(layer "F.SilkS")
			(hide yes)
			(effects
				(font
					(size 1.27 1.27)
				)
			)
		)
		(property "Value" "SC10U16V6KX-2GP"
			(at -0.0762 -5.1308 180)
			(unlocked yes)
			(layer "F.Fab")
			(hide yes)
			(effects
				(font
					(size 1.016 1.016)
					(thickness 0.1524)
				)
			)
		)
		(property "Device Type" "C1206H71"
			(at -0.127 -6.6548 180)
			(unlocked yes)
			(layer "F.Fab")
			(hide yes)
			(effects
				(font
					(size 1.016 1.016)
					(thickness 0.1524)
				)
			)
		)
		(duplicate_pad_numbers_are_jumpers no)
		(fp_line
			(start 1.016 2.2352)
			(end -1.016 2.2352)
			(stroke
				(width 0.1524)
				(type default)
			)
			(layer "F.SilkS")
		)
		(fp_line
			(start 1.016 0.8382)
			(end 1.016 2.2352)
			(stroke
				(width 0.1524)
				(type default)
			)
			(layer "F.SilkS")
		)
		(fp_line
			(start 1.016 -2.2352)
			(end 1.016 -0.8382)
			(stroke
				(width 0.1524)
				(type default)
			)
			(layer "F.SilkS")
		)
		(fp_line
			(start -1.016 2.2352)
			(end -1.016 0.8382)
			(stroke
				(width 0.1524)
				(type default)
			)
			(layer "F.SilkS")
		)
		(fp_line
			(start -1.016 -0.8382)
			(end -1.016 -2.2352)
			(stroke
				(width 0.1524)
				(type default)
			)
			(layer "F.SilkS")
		)
		(fp_line
			(start -1.016 -2.2352)
			(end 1.016 -2.2352)
			(stroke
				(width 0.1524)
				(type default)
			)
			(layer "F.SilkS")
		)
		(fp_rect
			(start -1.0922 2.3114)
			(end 1.0922 -2.3114)
			(stroke
				(width 0)
				(type default)
			)
			(fill no)
			(layer "F.CrtYd")
		)
		(fp_poly
			(pts
				(xy 1.0922 -2.3114) (xy 1.0922 2.3114) (xy -1.0922 2.3114) (xy -1.0922 -2.3114)
			)
			(stroke
				(width 0)
				(type default)
			)
			(fill no)
			(layer "F.Fab")
		)
		(pad "1" smd rect
			(at 0 -1.397 180)
			(size 1.651 1.27)
			(layers "F.Cu" "F.Mask" "F.Paste")
			(net "P5V_HDD30")
		)
		(pad "2" smd rect
			(at 0 1.397 180)
			(size 1.651 1.27)
			(layers "F.Cu" "F.Mask" "F.Paste")
			(net "GND")
		)
	)
	(footprint ""
		(layer "F.Cu")
		(at 321.634612 -273.660616 -90)
		(property "Reference" "C117"
			(at 0 0 270)
			(layer "F.SilkS")
			(hide yes)
			(effects
				(font
					(size 1.27 1.27)
				)
			)
		)
		(property "Value" "SCD01U16V1KX-GP"
			(at -2.8321 -1.7399 270)
			(unlocked yes)
			(layer "F.Fab")
			(hide yes)
			(effects
				(font
					(size 1.016 1.016)
					(thickness 0.1524)
				)
			)
		)
		(property "Device Type" "C0201H13"
			(at -2.8321 -3.2639 270)
			(unlocked yes)
			(layer "F.Fab")
			(hide yes)
			(effects
				(font
					(size 1.016 1.016)
					(thickness 0.1524)
				)
			)
		)
		(duplicate_pad_numbers_are_jumpers no)
		(fp_rect
			(start -0.2794 0.6477)
			(end 0.2794 -0.6477)
			(stroke
				(width 0)
				(type default)
			)
			(fill no)
			(layer "F.CrtYd")
		)
		(fp_rect
			(start -0.2794 0.6477)
			(end 0.2794 -0.6477)
			(stroke
				(width 0)
				(type default)
			)
			(fill no)
			(layer "F.Fab")
		)
		(pad "1" smd custom
			(at 0 -0.2794 270)
			(size 0.0762 0.0762)
			(layers "F.Cu" "F.Mask" "F.Paste")
			(net "SAS_HDD_RX_P6")
			(options
				(clearance outline)
				(anchor circle)
			)
			(primitives
				(gr_poly
					(pts
						(arc
							(start 0.1524 -0.127)
							(mid 0.137521 -0.162921)
							(end 0.1016 -0.1778)
						)
						(arc
							(start -0.1016 -0.1778)
							(mid -0.137521 -0.162921)
							(end -0.1524 -0.127)
						)
						(arc
							(start -0.1524 0.127)
							(mid -0.137521 0.162921)
							(end -0.1016 0.1778)
						)
						(arc
							(start 0.1016 0.1778)
							(mid 0.137521 0.162921)
							(end 0.1524 0.127)
						)
					)
					(width 0)
					(fill yes)
				)
			)
		)
		(pad "2" smd custom
			(at 0 0.2794 270)
			(size 0.0762 0.0762)
			(layers "F.Cu" "F.Mask" "F.Paste")
			(net "PHY_SCC_A_TO_DRV_A_6_DP")
			(options
				(clearance outline)
				(anchor circle)
			)
			(primitives
				(gr_poly
					(pts
						(arc
							(start 0.1524 -0.127)
							(mid 0.137521 -0.162921)
							(end 0.1016 -0.1778)
						)
						(arc
							(start -0.1016 -0.1778)
							(mid -0.137521 -0.162921)
							(end -0.1524 -0.127)
						)
						(arc
							(start -0.1524 0.127)
							(mid -0.137521 0.162921)
							(end -0.1016 0.1778)
						)
						(arc
							(start 0.1016 0.1778)
							(mid 0.137521 0.162921)
							(end 0.1524 0.127)
						)
					)
					(width 0)
					(fill yes)
				)
			)
		)
	)
	(footprint ""
		(layer "F.Cu")
		(at 267.5128 -230.3018)
		(property "Reference" "R98"
			(at 0 0 0)
			(layer "F.SilkS")
			(hide yes)
			(effects
				(font
					(size 1.27 1.27)
				)
			)
		)
		(property "Value" "4K7R2F-GP"
			(at 0.064008 -3.993896 0)
			(unlocked yes)
			(layer "F.Fab")
			(hide yes)
			(effects
				(font
					(size 1.016 1.016)
					(thickness 0.1524)
				)
			)
		)
		(property "Device Type" "R402H16"
			(at 0.064008 -5.517896 0)
			(unlocked yes)
			(layer "F.Fab")
			(hide yes)
			(effects
				(font
					(size 1.016 1.016)
					(thickness 0.1524)
				)
			)
		)
		(duplicate_pad_numbers_are_jumpers no)
		(fp_line
			(start -0.508 -0.9398)
			(end -0.508 0.9398)
			(stroke
				(width 0.1524)
				(type default)
			)
			(layer "F.SilkS")
		)
		(fp_line
			(start 0.508 -0.9398)
			(end -0.508 -0.9398)
			(stroke
				(width 0.1524)
				(type default)
			)
			(layer "F.SilkS")
		)
		(fp_rect
			(start -0.508 0.9398)
			(end 0.508 -0.9398)
			(stroke
				(width 0)
				(type default)
			)
			(fill no)
			(layer "F.CrtYd")
		)
		(fp_rect
			(start -0.508 0.9398)
			(end 0.508 -0.9398)
			(stroke
				(width 0)
				(type default)
			)
			(fill no)
			(layer "F.Fab")
		)
		(pad "1" smd custom
			(at 0 -0.4445)
			(size 0.1397 0.1397)
			(layers "F.Cu" "F.Mask" "F.Paste")
			(net "IO_EXP3_A2")
			(options
				(clearance outline)
				(anchor circle)
			)
			(primitives
				(gr_poly
					(pts
						(arc
							(start -0.1778 -0.2794)
							(mid -0.249642 -0.249642)
							(end -0.2794 -0.1778)
						)
						(arc
							(start -0.2794 0.1778)
							(mid -0.249642 0.249642)
							(end -0.1778 0.2794)
						)
						(arc
							(start 0.1778 0.2794)
							(mid 0.249642 0.249642)
							(end 0.2794 0.1778)
						)
						(arc
							(start 0.2794 -0.1778)
							(mid 0.249642 -0.249642)
							(end 0.1778 -0.2794)
						)
					)
					(width 0)
					(fill yes)
				)
			)
		)
		(pad "2" smd custom
			(at 0 0.4445)
			(size 0.1397 0.1397)
			(layers "F.Cu" "F.Mask" "F.Paste")
			(net "GND")
			(options
				(clearance outline)
				(anchor circle)
			)
			(primitives
				(gr_poly
					(pts
						(arc
							(start -0.1778 -0.2794)
							(mid -0.249642 -0.249642)
							(end -0.2794 -0.1778)
						)
						(arc
							(start -0.2794 0.1778)
							(mid -0.249642 0.249642)
							(end -0.1778 0.2794)
						)
						(arc
							(start 0.1778 0.2794)
							(mid 0.249642 0.249642)
							(end 0.2794 0.1778)
						)
						(arc
							(start 0.2794 -0.1778)
							(mid 0.249642 -0.249642)
							(end 0.1778 -0.2794)
						)
					)
					(width 0)
					(fill yes)
				)
			)
		)
	)
)
